(kicad_pcb
	(version 20260206)
	(generator "pcbnew")
	(generator_version "10.0")
	(general
		(thickness 1.6)
		(legacy_teardrops no)
	)
	(paper "A4")
	(title_block
		(title "04192023_DAF0TMB3IC0_F0TG_MB_C_brd_V02_OCP.brd")
		(comment 1 "Grand Teton / footprints 5444-5450 of 8354")
	)
	(layers
		(0 "F.Cu" signal "TOP")
		(4 "In1.Cu" signal "GND")
		(6 "In2.Cu" signal "IN1")
		(8 "In3.Cu" signal "GND1")
		(10 "In4.Cu" signal "IN2")
		(12 "In5.Cu" signal "GND2")
		(14 "In6.Cu" signal "IN3")
		(16 "In7.Cu" signal "GND3")
		(18 "In8.Cu" signal "VCC")
		(20 "In9.Cu" signal "VCC1")
		(22 "In10.Cu" signal "GND4")
		(24 "In11.Cu" signal "IN4")
		(26 "In12.Cu" signal "GND5")
		(28 "In13.Cu" signal "IN5")
		(30 "In14.Cu" signal "GND6")
		(32 "In15.Cu" signal "IN6")
		(34 "In16.Cu" signal "GND7")
		(2 "B.Cu" signal "BOTTOM")
		(9 "F.Adhes" user "F.Adhesive")
		(11 "B.Adhes" user "B.Adhesive")
		(13 "F.Paste" user "Package Geometry/Pastemask Top")
		(15 "B.Paste" user "Package Geometry/Pastemask Bottom")
		(5 "F.SilkS" user "Ref Des/Silkscreen Top")
		(7 "B.SilkS" user "Ref Des/Silkscreen Bottom")
		(1 "F.Mask" user "Board Geometry/Soldermask Top")
		(3 "B.Mask" user "Board Geometry/Soldermask Bottom")
		(17 "Dwgs.User" user "User.Drawings")
		(19 "Cmts.User" user "User.Comments")
		(21 "Eco1.User" user "User.Eco1")
		(23 "Eco2.User" user "User.Eco2")
		(25 "Edge.Cuts" user "Board Geometry/Outline")
		(27 "Margin" user)
		(31 "F.CrtYd" user "Package Geometry/Place Bound Top")
		(29 "B.CrtYd" user "Package Geometry/Place Bound Bottom")
		(35 "F.Fab" user "Ref Des/Assembly Top")
		(33 "B.Fab" user "Ref Des/Assembly Bottom")
	)
	(footprint ""
		(layer "B.Cu")
		(at 346.688664 -73.534778)
		(property "Reference" "Q86"
			(at 1.4224 -1.768348 0)
			(unlocked yes)
			(layer "B.SilkS")
			(effects
				(font
					(size 0.7874 0.5842)
					(thickness 0.1524)
				)
				(justify left mirror)
			)
		)
		(property "Value" ""
			(at 0 0 0)
			(layer "B.Fab")
			(effects
				(font
					(size 1.27 1.27)
				)
				(justify mirror)
			)
		)
		(duplicate_pad_numbers_are_jumpers no)
		(fp_line
			(start -1.332738 -1.100074)
			(end -1.332738 1.100074)
			(stroke
				(width 0.1524)
				(type default)
			)
			(layer "B.SilkS")
		)
		(fp_line
			(start -1.332738 1.100074)
			(end 1.332738 1.100074)
			(stroke
				(width 0.1524)
				(type default)
			)
			(layer "B.SilkS")
		)
		(fp_line
			(start -0.4826 -1.100074)
			(end -1.332738 -1.100074)
			(stroke
				(width 0.1524)
				(type default)
			)
			(layer "B.SilkS")
		)
		(fp_line
			(start 0 -0.541274)
			(end -0.4826 -1.100074)
			(stroke
				(width 0.1524)
				(type default)
			)
			(layer "B.SilkS")
		)
		(fp_line
			(start 0.4826 -1.100074)
			(end 0 -0.541274)
			(stroke
				(width 0.1524)
				(type default)
			)
			(layer "B.SilkS")
		)
		(fp_line
			(start 1.332738 -1.100074)
			(end 0.4826 -1.100074)
			(stroke
				(width 0.1524)
				(type default)
			)
			(layer "B.SilkS")
		)
		(fp_line
			(start 1.332738 1.100074)
			(end 1.332738 -1.100074)
			(stroke
				(width 0.1524)
				(type default)
			)
			(layer "B.SilkS")
		)
		(fp_poly
			(pts
				(xy 1.422654 -0.649986) (xy 2.12471 -1.001014) (xy 2.12471 -0.298958)
			)
			(stroke
				(width 0)
				(type default)
			)
			(fill yes)
			(layer "B.SilkS")
		)
		(fp_line
			(start -0.674878 -1.100074)
			(end -0.674878 1.100074)
			(stroke
				(width 0.1)
				(type default)
			)
			(layer "B.Fab")
		)
		(fp_line
			(start -0.674878 1.100074)
			(end 0.674878 1.100074)
			(stroke
				(width 0.1)
				(type default)
			)
			(layer "B.Fab")
		)
		(fp_line
			(start 0.674878 -1.100074)
			(end -0.674878 -1.100074)
			(stroke
				(width 0.1)
				(type default)
			)
			(layer "B.Fab")
		)
		(fp_line
			(start 0.674878 1.100074)
			(end 0.674878 -1.100074)
			(stroke
				(width 0.1)
				(type default)
			)
			(layer "B.Fab")
		)
		(fp_poly
			(pts
				(xy 2.2352 -0.298958) (xy 2.2352 -1.001014) (xy 1.533144 -0.649986)
			)
			(stroke
				(width 0)
				(type default)
			)
			(fill yes)
			(layer "B.Fab")
		)
		(pad "1" smd rect
			(at 0.94996 -0.649986 90)
			(size 0.4318 0.508)
			(layers "B.Cu" "B.Mask" "B.Paste")
			(net "GND")
		)
		(pad "2" smd rect
			(at 0.94996 0 90)
			(size 0.4318 0.508)
			(layers "B.Cu" "B.Mask" "B.Paste")
			(net "FM_LED_PWRGD_PVDD11_S3_P1")
		)
		(pad "3" smd rect
			(at 0.94996 0.649986 90)
			(size 0.4318 0.508)
			(layers "B.Cu" "B.Mask" "B.Paste")
			(net "LED_PWRGD_PVDD18_S5_P1_D")
		)
		(pad "4" smd rect
			(at -0.94996 0.649986 90)
			(size 0.4318 0.508)
			(layers "B.Cu" "B.Mask" "B.Paste")
			(net "GND")
		)
		(pad "5" smd rect
			(at -0.94996 0 90)
			(size 0.4318 0.508)
			(layers "B.Cu" "B.Mask" "B.Paste")
			(net "FM_LED_PWRGD_PVDD18_S5_P1")
		)
		(pad "6" smd rect
			(at -0.94996 -0.649986 90)
			(size 0.4318 0.508)
			(layers "B.Cu" "B.Mask" "B.Paste")
			(net "LED_PWRGD_PVDD11_S3_P1_D")
		)
	)
	(footprint ""
		(layer "B.Cu")
		(at 237.910624 -326.683624)
		(property "Reference" "R1235"
			(at 0 0 0)
			(layer "B.SilkS")
			(hide yes)
			(effects
				(font
					(size 1.27 1.27)
				)
				(justify mirror)
			)
		)
		(property "Value" ""
			(at 0 0 0)
			(layer "B.Fab")
			(effects
				(font
					(size 1.27 1.27)
				)
				(justify mirror)
			)
		)
		(duplicate_pad_numbers_are_jumpers no)
		(fp_line
			(start -0.7874 -0.4064)
			(end -0.7874 0.4064)
			(stroke
				(width 0.1524)
				(type default)
			)
			(layer "B.SilkS")
		)
		(fp_line
			(start -0.7874 0.4064)
			(end 0.7874 0.4064)
			(stroke
				(width 0.1524)
				(type default)
			)
			(layer "B.SilkS")
		)
		(fp_line
			(start 0.7874 -0.4064)
			(end -0.7874 -0.4064)
			(stroke
				(width 0.1524)
				(type default)
			)
			(layer "B.SilkS")
		)
		(fp_line
			(start 0.7874 0.4064)
			(end 0.7874 -0.4064)
			(stroke
				(width 0.1524)
				(type default)
			)
			(layer "B.SilkS")
		)
		(fp_line
			(start -0.67945 -0.3048)
			(end -0.67945 0.3048)
			(stroke
				(width 0.1)
				(type default)
			)
			(layer "B.Fab")
		)
		(fp_line
			(start -0.67945 0.3048)
			(end -0.120396 0.3048)
			(stroke
				(width 0.1)
				(type default)
			)
			(layer "B.Fab")
		)
		(fp_line
			(start -0.12065 -0.3048)
			(end -0.67945 -0.3048)
			(stroke
				(width 0.1)
				(type default)
			)
			(layer "B.Fab")
		)
		(fp_line
			(start -0.12065 -0.2794)
			(end -0.12065 -0.3048)
			(stroke
				(width 0.1)
				(type default)
			)
			(layer "B.Fab")
		)
		(fp_line
			(start -0.120396 0.2794)
			(end 0.12065 0.2794)
			(stroke
				(width 0.1)
				(type default)
			)
			(layer "B.Fab")
		)
		(fp_line
			(start -0.120396 0.3048)
			(end -0.120396 0.2794)
			(stroke
				(width 0.1)
				(type default)
			)
			(layer "B.Fab")
		)
		(fp_line
			(start 0.12065 -0.305054)
			(end 0.12065 -0.2794)
			(stroke
				(width 0.1)
				(type default)
			)
			(layer "B.Fab")
		)
		(fp_line
			(start 0.12065 -0.2794)
			(end -0.12065 -0.2794)
			(stroke
				(width 0.1)
				(type default)
			)
			(layer "B.Fab")
		)
		(fp_line
			(start 0.12065 0.2794)
			(end 0.12065 0.3048)
			(stroke
				(width 0.1)
				(type default)
			)
			(layer "B.Fab")
		)
		(fp_line
			(start 0.12065 0.3048)
			(end 0.67945 0.3048)
			(stroke
				(width 0.1)
				(type default)
			)
			(layer "B.Fab")
		)
		(fp_line
			(start 0.67945 -0.305054)
			(end 0.12065 -0.305054)
			(stroke
				(width 0.1)
				(type default)
			)
			(layer "B.Fab")
		)
		(fp_line
			(start 0.67945 0.3048)
			(end 0.67945 -0.305054)
			(stroke
				(width 0.1)
				(type default)
			)
			(layer "B.Fab")
		)
		(pad "1" smd circle
			(at 0.40005 0 180)
			(size 0 0)
			(layers "B.Cu" "B.Mask" "B.Paste")
			(net "PVDD_33_S5")
		)
		(pad "2" smd circle
			(at -0.40005 0 180)
			(size 0 0)
			(layers "B.Cu" "B.Mask" "B.Paste")
			(net "PVDD_33_S5_ADC")
		)
	)
	(footprint ""
		(layer "B.Cu")
		(at 314.85459 -76.889864 180)
		(property "Reference" "Q144"
			(at -1.40462 1.9939 0)
			(unlocked yes)
			(layer "B.SilkS")
			(effects
				(font
					(size 0.7874 0.5842)
					(thickness 0.1524)
				)
				(justify left mirror)
			)
		)
		(property "Value" ""
			(at 0 0 0)
			(layer "B.Fab")
			(effects
				(font
					(size 1.27 1.27)
				)
				(justify mirror)
			)
		)
		(duplicate_pad_numbers_are_jumpers no)
		(fp_line
			(start 1.332738 1.100074)
			(end 1.332738 -1.100074)
			(stroke
				(width 0.1524)
				(type default)
			)
			(layer "B.SilkS")
		)
		(fp_line
			(start 1.332738 -1.100074)
			(end 0.4826 -1.100074)
			(stroke
				(width 0.1524)
				(type default)
			)
			(layer "B.SilkS")
		)
		(fp_line
			(start 0.4826 -1.100074)
			(end 0 -0.541274)
			(stroke
				(width 0.1524)
				(type default)
			)
			(layer "B.SilkS")
		)
		(fp_line
			(start 0 -0.541274)
			(end -0.4826 -1.100074)
			(stroke
				(width 0.1524)
				(type default)
			)
			(layer "B.SilkS")
		)
		(fp_line
			(start -0.4826 -1.100074)
			(end -1.332738 -1.100074)
			(stroke
				(width 0.1524)
				(type default)
			)
			(layer "B.SilkS")
		)
		(fp_line
			(start -1.332738 1.100074)
			(end 1.332738 1.100074)
			(stroke
				(width 0.1524)
				(type default)
			)
			(layer "B.SilkS")
		)
		(fp_line
			(start -1.332738 -1.100074)
			(end -1.332738 1.100074)
			(stroke
				(width 0.1524)
				(type default)
			)
			(layer "B.SilkS")
		)
		(fp_poly
			(pts
				(xy 1.941576 -0.727202) (xy 2.643632 -1.07823) (xy 2.643632 -0.376174)
			)
			(stroke
				(width 0)
				(type default)
			)
			(fill yes)
			(layer "B.SilkS")
		)
		(fp_line
			(start 0.674878 1.100074)
			(end 0.674878 -1.100074)
			(stroke
				(width 0.1)
				(type default)
			)
			(layer "B.Fab")
		)
		(fp_line
			(start 0.674878 -1.100074)
			(end -0.674878 -1.100074)
			(stroke
				(width 0.1)
				(type default)
			)
			(layer "B.Fab")
		)
		(fp_line
			(start -0.674878 1.100074)
			(end 0.674878 1.100074)
			(stroke
				(width 0.1)
				(type default)
			)
			(layer "B.Fab")
		)
		(fp_line
			(start -0.674878 -1.100074)
			(end -0.674878 1.100074)
			(stroke
				(width 0.1)
				(type default)
			)
			(layer "B.Fab")
		)
		(fp_poly
			(pts
				(xy 2.2352 -0.298958) (xy 2.2352 -1.001014) (xy 1.533144 -0.649986)
			)
			(stroke
				(width 0)
				(type default)
			)
			(fill yes)
			(layer "B.Fab")
		)
		(pad "1" smd rect
			(at 0.94996 -0.649986 270)
			(size 0.4318 0.508)
			(layers "B.Cu" "B.Mask" "B.Paste")
			(net "GND")
		)
		(pad "2" smd rect
			(at 0.94996 0 270)
			(size 0.4318 0.508)
			(layers "B.Cu" "B.Mask" "B.Paste")
			(net "PWRGD_PS_PWROK_PLD")
		)
		(pad "3" smd rect
			(at 0.94996 0.649986 270)
			(size 0.4318 0.508)
			(layers "B.Cu" "B.Mask" "B.Paste")
			(net "PWRGD_PS_PWROK_PLD_ISO")
		)
		(pad "4" smd rect
			(at -0.94996 0.649986 270)
			(size 0.4318 0.508)
			(layers "B.Cu" "B.Mask" "B.Paste")
			(net "GND")
		)
		(pad "5" smd rect
			(at -0.94996 0 270)
			(size 0.4318 0.508)
			(layers "B.Cu" "B.Mask" "B.Paste")
			(net "PWRGD_PS_PWROK_PLD_N")
		)
		(pad "6" smd rect
			(at -0.94996 -0.649986 270)
			(size 0.4318 0.508)
			(layers "B.Cu" "B.Mask" "B.Paste")
			(net "PWRGD_PS_PWROK_PLD_N")
		)
	)
	(footprint ""
		(layer "B.Cu")
		(at 342.066118 -169.643552 90)
		(property "Reference" "PR447"
			(at 0 0 90)
			(layer "B.SilkS")
			(hide yes)
			(effects
				(font
					(size 1.27 1.27)
				)
				(justify mirror)
			)
		)
		(property "Value" ""
			(at 0 0 90)
			(layer "B.Fab")
			(effects
				(font
					(size 1.27 1.27)
				)
				(justify mirror)
			)
		)
		(duplicate_pad_numbers_are_jumpers no)
		(fp_line
			(start 0.7874 -0.4064)
			(end -0.7874 -0.4064)
			(stroke
				(width 0.1524)
				(type default)
			)
			(layer "B.SilkS")
		)
		(fp_line
			(start -0.7874 -0.4064)
			(end -0.7874 0.4064)
			(stroke
				(width 0.1524)
				(type default)
			)
			(layer "B.SilkS")
		)
		(fp_line
			(start 0.7874 0.4064)
			(end 0.7874 -0.4064)
			(stroke
				(width 0.1524)
				(type default)
			)
			(layer "B.SilkS")
		)
		(fp_line
			(start -0.7874 0.4064)
			(end 0.7874 0.4064)
			(stroke
				(width 0.1524)
				(type default)
			)
			(layer "B.SilkS")
		)
		(fp_line
			(start 0.67945 -0.305054)
			(end 0.12065 -0.305054)
			(stroke
				(width 0.1)
				(type default)
			)
			(layer "B.Fab")
		)
		(fp_line
			(start 0.12065 -0.305054)
			(end 0.12065 -0.2794)
			(stroke
				(width 0.1)
				(type default)
			)
			(layer "B.Fab")
		)
		(fp_line
			(start -0.12065 -0.3048)
			(end -0.67945 -0.3048)
			(stroke
				(width 0.1)
				(type default)
			)
			(layer "B.Fab")
		)
		(fp_line
			(start -0.67945 -0.3048)
			(end -0.67945 0.3048)
			(stroke
				(width 0.1)
				(type default)
			)
			(layer "B.Fab")
		)
		(fp_line
			(start 0.12065 -0.2794)
			(end -0.12065 -0.2794)
			(stroke
				(width 0.1)
				(type default)
			)
			(layer "B.Fab")
		)
		(fp_line
			(start -0.12065 -0.2794)
			(end -0.12065 -0.3048)
			(stroke
				(width 0.1)
				(type default)
			)
			(layer "B.Fab")
		)
		(fp_line
			(start 0.12065 0.2794)
			(end 0.12065 0.3048)
			(stroke
				(width 0.1)
				(type default)
			)
			(layer "B.Fab")
		)
		(fp_line
			(start -0.120396 0.2794)
			(end 0.12065 0.2794)
			(stroke
				(width 0.1)
				(type default)
			)
			(layer "B.Fab")
		)
		(fp_line
			(start 0.67945 0.3048)
			(end 0.67945 -0.305054)
			(stroke
				(width 0.1)
				(type default)
			)
			(layer "B.Fab")
		)
		(fp_line
			(start 0.12065 0.3048)
			(end 0.67945 0.3048)
			(stroke
				(width 0.1)
				(type default)
			)
			(layer "B.Fab")
		)
		(fp_line
			(start -0.120396 0.3048)
			(end -0.120396 0.2794)
			(stroke
				(width 0.1)
				(type default)
			)
			(layer "B.Fab")
		)
		(fp_line
			(start -0.67945 0.3048)
			(end -0.120396 0.3048)
			(stroke
				(width 0.1)
				(type default)
			)
			(layer "B.Fab")
		)
		(pad "1" smd circle
			(at 0.40005 0 270)
			(size 0 0)
			(layers "B.Cu" "B.Mask" "B.Paste")
			(net "PVDDCR_CPU0_P0")
		)
		(pad "2" smd circle
			(at -0.40005 0 270)
			(size 0 0)
			(layers "B.Cu" "B.Mask" "B.Paste")
			(net "GND")
		)
	)
	(footprint ""
		(layer "B.Cu")
		(at 356.311454 -264.35431)
		(property "Reference" "C2607"
			(at 0 0 0)
			(layer "B.SilkS")
			(hide yes)
			(effects
				(font
					(size 1.27 1.27)
				)
				(justify mirror)
			)
		)
		(property "Value" ""
			(at 0 0 0)
			(layer "B.Fab")
			(effects
				(font
					(size 1.27 1.27)
				)
				(justify mirror)
			)
		)
		(duplicate_pad_numbers_are_jumpers no)
		(fp_line
			(start -0.7874 -0.4064)
			(end -0.7874 0.4064)
			(stroke
				(width 0.1524)
				(type default)
			)
			(layer "B.SilkS")
		)
		(fp_line
			(start -0.7874 0.4064)
			(end 0.7874 0.4064)
			(stroke
				(width 0.1524)
				(type default)
			)
			(layer "B.SilkS")
		)
		(fp_line
			(start 0.7874 -0.4064)
			(end -0.7874 -0.4064)
			(stroke
				(width 0.1524)
				(type default)
			)
			(layer "B.SilkS")
		)
		(fp_line
			(start 0.7874 0.4064)
			(end 0.7874 -0.4064)
			(stroke
				(width 0.1524)
				(type default)
			)
			(layer "B.SilkS")
		)
		(fp_line
			(start -0.67945 -0.3048)
			(end -0.67945 0.3048)
			(stroke
				(width 0.1)
				(type default)
			)
			(layer "B.Fab")
		)
		(fp_line
			(start -0.67945 0.3048)
			(end -0.120396 0.3048)
			(stroke
				(width 0.1)
				(type default)
			)
			(layer "B.Fab")
		)
		(fp_line
			(start -0.12065 -0.3048)
			(end -0.67945 -0.3048)
			(stroke
				(width 0.1)
				(type default)
			)
			(layer "B.Fab")
		)
		(fp_line
			(start -0.12065 -0.2794)
			(end -0.12065 -0.3048)
			(stroke
				(width 0.1)
				(type default)
			)
			(layer "B.Fab")
		)
		(fp_line
			(start -0.120396 0.2794)
			(end 0.12065 0.2794)
			(stroke
				(width 0.1)
				(type default)
			)
			(layer "B.Fab")
		)
		(fp_line
			(start -0.120396 0.3048)
			(end -0.120396 0.2794)
			(stroke
				(width 0.1)
				(type default)
			)
			(layer "B.Fab")
		)
		(fp_line
			(start 0.12065 -0.305054)
			(end 0.12065 -0.2794)
			(stroke
				(width 0.1)
				(type default)
			)
			(layer "B.Fab")
		)
		(fp_line
			(start 0.12065 -0.2794)
			(end -0.12065 -0.2794)
			(stroke
				(width 0.1)
				(type default)
			)
			(layer "B.Fab")
		)
		(fp_line
			(start 0.12065 0.2794)
			(end 0.12065 0.3048)
			(stroke
				(width 0.1)
				(type default)
			)
			(layer "B.Fab")
		)
		(fp_line
			(start 0.12065 0.3048)
			(end 0.67945 0.3048)
			(stroke
				(width 0.1)
				(type default)
			)
			(layer "B.Fab")
		)
		(fp_line
			(start 0.67945 -0.305054)
			(end 0.12065 -0.305054)
			(stroke
				(width 0.1)
				(type default)
			)
			(layer "B.Fab")
		)
		(fp_line
			(start 0.67945 0.3048)
			(end 0.67945 -0.305054)
			(stroke
				(width 0.1)
				(type default)
			)
			(layer "B.Fab")
		)
		(pad "1" smd circle
			(at 0.40005 0 180)
			(size 0 0)
			(layers "B.Cu" "B.Mask" "B.Paste")
			(net "PVDD11_S3_P0")
		)
		(pad "2" smd circle
			(at -0.40005 0 180)
			(size 0 0)
			(layers "B.Cu" "B.Mask" "B.Paste")
			(net "GND")
		)
	)
	(footprint ""
		(layer "B.Cu")
		(at 97.996248 -182.555134 -90)
		(property "Reference" "PC296_3"
			(at 0 0 90)
			(layer "B.SilkS")
			(hide yes)
			(effects
				(font
					(size 1.27 1.27)
				)
				(justify mirror)
			)
		)
		(property "Value" ""
			(at 0 0 90)
			(layer "B.Fab")
			(effects
				(font
					(size 1.27 1.27)
				)
				(justify mirror)
			)
		)
		(duplicate_pad_numbers_are_jumpers no)
		(fp_line
			(start -1.524 0.762)
			(end 1.524 0.762)
			(stroke
				(width 0.1524)
				(type default)
			)
			(layer "B.SilkS")
		)
		(fp_line
			(start 1.524 0.762)
			(end 1.524 -0.762)
			(stroke
				(width 0.1524)
				(type default)
			)
			(layer "B.SilkS")
		)
		(fp_line
			(start -1.524 -0.762)
			(end -1.524 0.762)
			(stroke
				(width 0.1524)
				(type default)
			)
			(layer "B.SilkS")
		)
		(fp_line
			(start 1.524 -0.762)
			(end -1.524 -0.762)
			(stroke
				(width 0.1524)
				(type default)
			)
			(layer "B.SilkS")
		)
		(fp_line
			(start -1.1049 0.724916)
			(end -1.1049 -0.724916)
			(stroke
				(width 0.1)
				(type default)
			)
			(layer "B.Fab")
		)
		(fp_line
			(start 1.1049 0.724916)
			(end -1.1049 0.724916)
			(stroke
				(width 0.1)
				(type default)
			)
			(layer "B.Fab")
		)
		(fp_line
			(start -1.1049 -0.724916)
			(end 1.1049 -0.724916)
			(stroke
				(width 0.1)
				(type default)
			)
			(layer "B.Fab")
		)
		(fp_line
			(start 1.1049 -0.724916)
			(end 1.1049 0.724916)
			(stroke
				(width 0.1)
				(type default)
			)
			(layer "B.Fab")
		)
		(pad "1" smd rect
			(at 0.889 0 270)
			(size 1.016 1.27)
			(layers "B.Cu" "B.Mask" "B.Paste")
			(net "SW_P12V_AUX_PVDDCR_CPU0_P1_FLT")
		)
		(pad "2" smd rect
			(at -0.889 0 270)
			(size 1.016 1.27)
			(layers "B.Cu" "B.Mask" "B.Paste")
			(net "GND")
		)
	)
	(footprint ""
		(layer "B.Cu")
		(at 255.905 -339.63864 180)
		(property "Reference" "R828"
			(at 0 0 0)
			(layer "B.SilkS")
			(hide yes)
			(effects
				(font
					(size 1.27 1.27)
				)
				(justify mirror)
			)
		)
		(property "Value" ""
			(at 0 0 0)
			(layer "B.Fab")
			(effects
				(font
					(size 1.27 1.27)
				)
				(justify mirror)
			)
		)
		(duplicate_pad_numbers_are_jumpers no)
		(fp_line
			(start 0.32512 0.175006)
			(end 0.32512 -0.175006)
			(stroke
				(width 0.1)
				(type default)
			)
			(layer "B.Fab")
		)
		(fp_line
			(start 0.32512 -0.175006)
			(end -0.32512 -0.175006)
			(stroke
				(width 0.1)
				(type default)
			)
			(layer "B.Fab")
		)
		(fp_line
			(start -0.32512 0.175006)
			(end 0.32512 0.175006)
			(stroke
				(width 0.1)
				(type default)
			)
			(layer "B.Fab")
		)
		(fp_line
			(start -0.32512 -0.175006)
			(end -0.32512 0.175006)
			(stroke
				(width 0.1)
				(type default)
			)
			(layer "B.Fab")
		)
		(pad "1" smd rect
			(at 0.2667 0)
			(size 0.3048 0.381)
			(layers "B.Cu" "B.Mask" "B.Paste")
			(net "SMB_RT_CPU0_P1_ROM_MUX_2D_R_SDA")
		)
		(pad "2" smd rect
			(at -0.2667 0 180)
			(size 0.3048 0.381)
			(layers "B.Cu" "B.Mask" "B.Paste")
			(net "SMB_RT_CPU0_P1_ROM_MUX_2D_SDA")
		)
	)
)
